# T6G (Grand Teton) — schematic netlist excerpt (pin names and nets, part order shuffled) for the footprints in the layout excerpt that follows; sources: Cadence DE-HDL packaged netlist, KiCad conversion of 04192023_DAF0TMB3IC0_F0TG_MB_C_brd_V02_OCP.brd

R1594  Q_RES  33.2 1% CHIP  pkg 0402LF  page 133 : A = OCP_SFF_WAKE_BUFF_N ; B = OCP_SFF_WAKE_BUFF_R_N
C6526  Q_CAP_DIFFBUS  DIFF BUS_0.22UF 6.3V 20% X6S  pkg C0201  page 275 : \1\ = P5E_CPU0_P0_TX_BUF_C_DN<12> ; \2\ = P5E_CPU0_P0_TX_BUF_DN<12>
R4547  Q_RES  100K 1% EMPTY  pkg 0402LF  page 124 : A = P3V3_AUX ; B = SWB_HSC_EN

(kicad_pcb
	(version 20260206)
	(generator "pcbnew")
	(generator_version "10.0")
	(general
		(thickness 1.6)
		(legacy_teardrops no)
	)
	(paper "A4")
	(title_block
		(title "04192023_DAF0TMB3IC0_F0TG_MB_C_brd_V02_OCP.brd")
		(comment 1 "Grand Teton / footprints 4117-4119 of 8354")
	)
	(layers
		(0 "F.Cu" signal "TOP")
		(4 "In1.Cu" signal "GND")
		(6 "In2.Cu" signal "IN1")
		(8 "In3.Cu" signal "GND1")
		(10 "In4.Cu" signal "IN2")
		(12 "In5.Cu" signal "GND2")
		(14 "In6.Cu" signal "IN3")
		(16 "In7.Cu" signal "GND3")
		(18 "In8.Cu" signal "VCC")
		(20 "In9.Cu" signal "VCC1")
		(22 "In10.Cu" signal "GND4")
		(24 "In11.Cu" signal "IN4")
		(26 "In12.Cu" signal "GND5")
		(28 "In13.Cu" signal "IN5")
		(30 "In14.Cu" signal "GND6")
		(32 "In15.Cu" signal "IN6")
		(34 "In16.Cu" signal "GND7")
		(2 "B.Cu" signal "BOTTOM")
		(9 "F.Adhes" user "F.Adhesive")
		(11 "B.Adhes" user "B.Adhesive")
		(13 "F.Paste" user "Package Geometry/Pastemask Top")
		(15 "B.Paste" user "Package Geometry/Pastemask Bottom")
		(5 "F.SilkS" user "Ref Des/Silkscreen Top")
		(7 "B.SilkS" user "Ref Des/Silkscreen Bottom")
		(1 "F.Mask" user "Board Geometry/Soldermask Top")
		(3 "B.Mask" user "Board Geometry/Soldermask Bottom")
		(17 "Dwgs.User" user "User.Drawings")
		(19 "Cmts.User" user "User.Comments")
		(21 "Eco1.User" user "User.Eco1")
		(23 "Eco2.User" user "User.Eco2")
		(25 "Edge.Cuts" user "Board Geometry/Outline")
		(27 "Margin" user)
		(31 "F.CrtYd" user "Package Geometry/Place Bound Top")
		(29 "B.CrtYd" user "Package Geometry/Place Bound Bottom")
		(35 "F.Fab" user "Ref Des/Assembly Top")
		(33 "B.Fab" user "Ref Des/Assembly Bottom")
	)
	(footprint ""
		(layer "F.Cu")
		(at 351.486216 -440.211972)
		(property "Reference" "R4547"
			(at 0 0 0)
			(layer "F.SilkS")
			(hide yes)
			(effects
				(font
					(size 1.27 1.27)
				)
			)
		)
		(property "Value" ""
			(at 0 0 0)
			(layer "F.Fab")
			(effects
				(font
					(size 1.27 1.27)
				)
			)
		)
		(duplicate_pad_numbers_are_jumpers no)
		(fp_line
			(start -0.7874 -0.4064)
			(end 0.7874 -0.4064)
			(stroke
				(width 0.1524)
				(type default)
			)
			(layer "F.SilkS")
		)
		(fp_line
			(start -0.7874 0.4064)
			(end -0.7874 -0.4064)
			(stroke
				(width 0.1524)
				(type default)
			)
			(layer "F.SilkS")
		)
		(fp_line
			(start 0.7874 -0.4064)
			(end 0.7874 0.4064)
			(stroke
				(width 0.1524)
				(type default)
			)
			(layer "F.SilkS")
		)
		(fp_line
			(start 0.7874 0.4064)
			(end -0.7874 0.4064)
			(stroke
				(width 0.1524)
				(type default)
			)
			(layer "F.SilkS")
		)
		(fp_line
			(start -0.67945 -0.305054)
			(end -0.12065 -0.305054)
			(stroke
				(width 0.1)
				(type default)
			)
			(layer "F.Fab")
		)
		(fp_line
			(start -0.67945 0.3048)
			(end -0.67945 -0.305054)
			(stroke
				(width 0.1)
				(type default)
			)
			(layer "F.Fab")
		)
		(fp_line
			(start -0.12065 -0.305054)
			(end -0.12065 -0.2794)
			(stroke
				(width 0.1)
				(type default)
			)
			(layer "F.Fab")
		)
		(fp_line
			(start -0.12065 -0.2794)
			(end 0.12065 -0.2794)
			(stroke
				(width 0.1)
				(type default)
			)
			(layer "F.Fab")
		)
		(fp_line
			(start -0.12065 0.2794)
			(end -0.12065 0.3048)
			(stroke
				(width 0.1)
				(type default)
			)
			(layer "F.Fab")
		)
		(fp_line
			(start -0.12065 0.3048)
			(end -0.67945 0.3048)
			(stroke
				(width 0.1)
				(type default)
			)
			(layer "F.Fab")
		)
		(fp_line
			(start 0.120396 0.2794)
			(end -0.12065 0.2794)
			(stroke
				(width 0.1)
				(type default)
			)
			(layer "F.Fab")
		)
		(fp_line
			(start 0.120396 0.3048)
			(end 0.120396 0.2794)
			(stroke
				(width 0.1)
				(type default)
			)
			(layer "F.Fab")
		)
		(fp_line
			(start 0.12065 -0.3048)
			(end 0.67945 -0.3048)
			(stroke
				(width 0.1)
				(type default)
			)
			(layer "F.Fab")
		)
		(fp_line
			(start 0.12065 -0.2794)
			(end 0.12065 -0.3048)
			(stroke
				(width 0.1)
				(type default)
			)
			(layer "F.Fab")
		)
		(fp_line
			(start 0.67945 -0.3048)
			(end 0.67945 0.3048)
			(stroke
				(width 0.1)
				(type default)
			)
			(layer "F.Fab")
		)
		(fp_line
			(start 0.67945 0.3048)
			(end 0.120396 0.3048)
			(stroke
				(width 0.1)
				(type default)
			)
			(layer "F.Fab")
		)
		(pad "1" smd circle
			(at -0.40005 0)
			(size 0 0)
			(layers "F.Cu" "F.Mask" "F.Paste")
			(net "P3V3_AUX")
		)
		(pad "2" smd circle
			(at 0.40005 0)
			(size 0 0)
			(layers "F.Cu" "F.Mask" "F.Paste")
			(net "SWB_HSC_EN")
		)
	)
	(footprint ""
		(layer "F.Cu")
		(at 340.527386 -416.899344 -90)
		(property "Reference" "C6526"
			(at 0 0 270)
			(layer "F.SilkS")
			(hide yes)
			(effects
				(font
					(size 1.27 1.27)
				)
			)
		)
		(property "Value" ""
			(at 0 0 270)
			(layer "F.Fab")
			(effects
				(font
					(size 1.27 1.27)
				)
			)
		)
		(duplicate_pad_numbers_are_jumpers no)
		(fp_line
			(start -0.299974 0.150114)
			(end -0.299974 -0.150114)
			(stroke
				(width 0.1)
				(type default)
			)
			(layer "F.Fab")
		)
		(fp_line
			(start 0.299974 0.150114)
			(end -0.299974 0.150114)
			(stroke
				(width 0.1)
				(type default)
			)
			(layer "F.Fab")
		)
		(fp_line
			(start -0.299974 -0.150114)
			(end 0.299974 -0.150114)
			(stroke
				(width 0.1)
				(type default)
			)
			(layer "F.Fab")
		)
		(fp_line
			(start 0.299974 -0.150114)
			(end 0.299974 0.150114)
			(stroke
				(width 0.1)
				(type default)
			)
			(layer "F.Fab")
		)
		(pad "1" smd rect
			(at -0.2667 0 270)
			(size 0.3048 0.381)
			(layers "F.Cu" "F.Mask" "F.Paste")
			(net "P5E_CPU0_P0_TX_BUF_C_DN<12>")
		)
		(pad "2" smd rect
			(at 0.2667 0 270)
			(size 0.3048 0.381)
			(layers "F.Cu" "F.Mask" "F.Paste")
			(net "P5E_CPU0_P0_TX_BUF_DN<12>")
		)
	)
	(footprint ""
		(layer "F.Cu")
		(at 463.18932 -37.549836)
		(property "Reference" "R1594"
			(at 0 0 0)
			(layer "F.SilkS")
			(hide yes)
			(effects
				(font
					(size 1.27 1.27)
				)
			)
		)
		(property "Value" ""
			(at 0 0 0)
			(layer "F.Fab")
			(effects
				(font
					(size 1.27 1.27)
				)
			)
		)
		(duplicate_pad_numbers_are_jumpers no)
		(fp_line
			(start -0.7874 -0.4064)
			(end 0.7874 -0.4064)
			(stroke
				(width 0.1524)
				(type default)
			)
			(layer "F.SilkS")
		)
		(fp_line
			(start -0.7874 0.4064)
			(end -0.7874 -0.4064)
			(stroke
				(width 0.1524)
				(type default)
			)
			(layer "F.SilkS")
		)
		(fp_line
			(start 0.7874 -0.4064)
			(end 0.7874 0.4064)
			(stroke
				(width 0.1524)
				(type default)
			)
			(layer "F.SilkS")
		)
		(fp_line
			(start 0.7874 0.4064)
			(end -0.7874 0.4064)
			(stroke
				(width 0.1524)
				(type default)
			)
			(layer "F.SilkS")
		)
		(fp_line
			(start -0.67945 -0.305054)
			(end -0.12065 -0.305054)
			(stroke
				(width 0.1)
				(type default)
			)
			(layer "F.Fab")
		)
		(fp_line
			(start -0.67945 0.3048)
			(end -0.67945 -0.305054)
			(stroke
				(width 0.1)
				(type default)
			)
			(layer "F.Fab")
		)
		(fp_line
			(start -0.12065 -0.305054)
			(end -0.12065 -0.2794)
			(stroke
				(width 0.1)
				(type default)
			)
			(layer "F.Fab")
		)
		(fp_line
			(start -0.12065 -0.2794)
			(end 0.12065 -0.2794)
			(stroke
				(width 0.1)
				(type default)
			)
			(layer "F.Fab")
		)
		(fp_line
			(start -0.12065 0.2794)
			(end -0.12065 0.3048)
			(stroke
				(width 0.1)
				(type default)
			)
			(layer "F.Fab")
		)
		(fp_line
			(start -0.12065 0.3048)
			(end -0.67945 0.3048)
			(stroke
				(width 0.1)
				(type default)
			)
			(layer "F.Fab")
		)
		(fp_line
			(start 0.120396 0.2794)
			(end -0.12065 0.2794)
			(stroke
				(width 0.1)
				(type default)
			)
			(layer "F.Fab")
		)
		(fp_line
			(start 0.120396 0.3048)
			(end 0.120396 0.2794)
			(stroke
				(width 0.1)
				(type default)
			)
			(layer "F.Fab")
		)
		(fp_line
			(start 0.12065 -0.3048)
			(end 0.67945 -0.3048)
			(stroke
				(width 0.1)
				(type default)
			)
			(layer "F.Fab")
		)
		(fp_line
			(start 0.12065 -0.2794)
			(end 0.12065 -0.3048)
			(stroke
				(width 0.1)
				(type default)
			)
			(layer "F.Fab")
		)
		(fp_line
			(start 0.67945 -0.3048)
			(end 0.67945 0.3048)
			(stroke
				(width 0.1)
				(type default)
			)
			(layer "F.Fab")
		)
		(fp_line
			(start 0.67945 0.3048)
			(end 0.120396 0.3048)
			(stroke
				(width 0.1)
				(type default)
			)
			(layer "F.Fab")
		)
		(pad "1" smd circle
			(at -0.40005 0)
			(size 0 0)
			(layers "F.Cu" "F.Mask" "F.Paste")
			(net "OCP_SFF_WAKE_BUFF_N")
		)
		(pad "2" smd circle
			(at 0.40005 0)
			(size 0 0)
			(layers "F.Cu" "F.Mask" "F.Paste")
			(net "OCP_SFF_WAKE_BUFF_R_N")
		)
	)
)
